# T6G (Grand Teton) — schematic netlist excerpt (pin names and nets, part order shuffled) for the footprints in the layout excerpt that follows; sources: Cadence DE-HDL packaged netlist, KiCad conversion of 04192023_DAF0TMB3IC0_F0TG_MB_C_brd_V02_OCP.brd

PC6614_1  Q_CAP  22UF 16V 20% X6S  pkg C0805  page 365 : A = SW_P12V_AUX_P0V9_RETIMER_CPU1_FLT ; B = GND
R6129  Q_RES  1K 1% CHIP  pkg 0402LF  page 84 : A = FM_BOARD_SKU_ID0 ; B = GND
C2461  Q_CAP  22UF 4V 20% X6S  pkg C0402  page 74 : A = PVDDCR_SOC_P1 ; B = GND

(kicad_pcb
	(version 20260206)
	(generator "pcbnew")
	(generator_version "10.0")
	(general
		(thickness 1.6)
		(legacy_teardrops no)
	)
	(paper "A4")
	(title_block
		(title "04192023_DAF0TMB3IC0_F0TG_MB_C_brd_V02_OCP.brd")
		(comment 1 "Grand Teton / footprints 6390-6392 of 8354")
	)
	(layers
		(0 "F.Cu" signal "TOP")
		(4 "In1.Cu" signal "GND")
		(6 "In2.Cu" signal "IN1")
		(8 "In3.Cu" signal "GND1")
		(10 "In4.Cu" signal "IN2")
		(12 "In5.Cu" signal "GND2")
		(14 "In6.Cu" signal "IN3")
		(16 "In7.Cu" signal "GND3")
		(18 "In8.Cu" signal "VCC")
		(20 "In9.Cu" signal "VCC1")
		(22 "In10.Cu" signal "GND4")
		(24 "In11.Cu" signal "IN4")
		(26 "In12.Cu" signal "GND5")
		(28 "In13.Cu" signal "IN5")
		(30 "In14.Cu" signal "GND6")
		(32 "In15.Cu" signal "IN6")
		(34 "In16.Cu" signal "GND7")
		(2 "B.Cu" signal "BOTTOM")
		(9 "F.Adhes" user "F.Adhesive")
		(11 "B.Adhes" user "B.Adhesive")
		(13 "F.Paste" user "Package Geometry/Pastemask Top")
		(15 "B.Paste" user "Package Geometry/Pastemask Bottom")
		(5 "F.SilkS" user "Ref Des/Silkscreen Top")
		(7 "B.SilkS" user "Ref Des/Silkscreen Bottom")
		(1 "F.Mask" user "Board Geometry/Soldermask Top")
		(3 "B.Mask" user "Board Geometry/Soldermask Bottom")
		(17 "Dwgs.User" user "User.Drawings")
		(19 "Cmts.User" user "User.Comments")
		(21 "Eco1.User" user "User.Eco1")
		(23 "Eco2.User" user "User.Eco2")
		(25 "Edge.Cuts" user "Board Geometry/Outline")
		(27 "Margin" user)
		(31 "F.CrtYd" user "Package Geometry/Place Bound Top")
		(29 "B.CrtYd" user "Package Geometry/Place Bound Bottom")
		(35 "F.Fab" user "Ref Des/Assembly Top")
		(33 "B.Fab" user "Ref Des/Assembly Bottom")
	)
	(footprint ""
		(layer "B.Cu")
		(at 123.611386 -258.830318)
		(property "Reference" "C2461"
			(at 0 0 0)
			(layer "B.SilkS")
			(hide yes)
			(effects
				(font
					(size 1.27 1.27)
				)
				(justify mirror)
			)
		)
		(property "Value" ""
			(at 0 0 0)
			(layer "B.Fab")
			(effects
				(font
					(size 1.27 1.27)
				)
				(justify mirror)
			)
		)
		(duplicate_pad_numbers_are_jumpers no)
		(fp_line
			(start -0.7874 -0.4064)
			(end -0.7874 0.4064)
			(stroke
				(width 0.1524)
				(type default)
			)
			(layer "B.SilkS")
		)
		(fp_line
			(start -0.7874 0.4064)
			(end 0.7874 0.4064)
			(stroke
				(width 0.1524)
				(type default)
			)
			(layer "B.SilkS")
		)
		(fp_line
			(start 0.7874 -0.4064)
			(end -0.7874 -0.4064)
			(stroke
				(width 0.1524)
				(type default)
			)
			(layer "B.SilkS")
		)
		(fp_line
			(start 0.7874 0.4064)
			(end 0.7874 -0.4064)
			(stroke
				(width 0.1524)
				(type default)
			)
			(layer "B.SilkS")
		)
		(fp_line
			(start -0.67945 -0.3048)
			(end -0.67945 0.3048)
			(stroke
				(width 0.1)
				(type default)
			)
			(layer "B.Fab")
		)
		(fp_line
			(start -0.67945 0.3048)
			(end -0.120396 0.3048)
			(stroke
				(width 0.1)
				(type default)
			)
			(layer "B.Fab")
		)
		(fp_line
			(start -0.12065 -0.3048)
			(end -0.67945 -0.3048)
			(stroke
				(width 0.1)
				(type default)
			)
			(layer "B.Fab")
		)
		(fp_line
			(start -0.12065 -0.2794)
			(end -0.12065 -0.3048)
			(stroke
				(width 0.1)
				(type default)
			)
			(layer "B.Fab")
		)
		(fp_line
			(start -0.120396 0.2794)
			(end 0.12065 0.2794)
			(stroke
				(width 0.1)
				(type default)
			)
			(layer "B.Fab")
		)
		(fp_line
			(start -0.120396 0.3048)
			(end -0.120396 0.2794)
			(stroke
				(width 0.1)
				(type default)
			)
			(layer "B.Fab")
		)
		(fp_line
			(start 0.12065 -0.305054)
			(end 0.12065 -0.2794)
			(stroke
				(width 0.1)
				(type default)
			)
			(layer "B.Fab")
		)
		(fp_line
			(start 0.12065 -0.2794)
			(end -0.12065 -0.2794)
			(stroke
				(width 0.1)
				(type default)
			)
			(layer "B.Fab")
		)
		(fp_line
			(start 0.12065 0.2794)
			(end 0.12065 0.3048)
			(stroke
				(width 0.1)
				(type default)
			)
			(layer "B.Fab")
		)
		(fp_line
			(start 0.12065 0.3048)
			(end 0.67945 0.3048)
			(stroke
				(width 0.1)
				(type default)
			)
			(layer "B.Fab")
		)
		(fp_line
			(start 0.67945 -0.305054)
			(end 0.12065 -0.305054)
			(stroke
				(width 0.1)
				(type default)
			)
			(layer "B.Fab")
		)
		(fp_line
			(start 0.67945 0.3048)
			(end 0.67945 -0.305054)
			(stroke
				(width 0.1)
				(type default)
			)
			(layer "B.Fab")
		)
		(pad "1" smd circle
			(at 0.40005 0 180)
			(size 0 0)
			(layers "B.Cu" "B.Mask" "B.Paste")
			(net "PVDDCR_SOC_P1")
		)
		(pad "2" smd circle
			(at -0.40005 0 180)
			(size 0 0)
			(layers "B.Cu" "B.Mask" "B.Paste")
			(net "GND")
		)
	)
	(footprint ""
		(layer "B.Cu")
		(at 19.91487 -388.789926 90)
		(property "Reference" "PC6614_1"
			(at 0 0 90)
			(layer "B.SilkS")
			(hide yes)
			(effects
				(font
					(size 1.27 1.27)
				)
				(justify mirror)
			)
		)
		(property "Value" ""
			(at 0 0 90)
			(layer "B.Fab")
			(effects
				(font
					(size 1.27 1.27)
				)
				(justify mirror)
			)
		)
		(duplicate_pad_numbers_are_jumpers no)
		(fp_line
			(start 1.524 -0.762)
			(end -1.524 -0.762)
			(stroke
				(width 0.1524)
				(type default)
			)
			(layer "B.SilkS")
		)
		(fp_line
			(start -1.524 -0.762)
			(end -1.524 0.762)
			(stroke
				(width 0.1524)
				(type default)
			)
			(layer "B.SilkS")
		)
		(fp_line
			(start 1.524 0.762)
			(end 1.524 -0.762)
			(stroke
				(width 0.1524)
				(type default)
			)
			(layer "B.SilkS")
		)
		(fp_line
			(start -1.524 0.762)
			(end 1.524 0.762)
			(stroke
				(width 0.1524)
				(type default)
			)
			(layer "B.SilkS")
		)
		(fp_line
			(start 1.1049 -0.724916)
			(end 1.1049 0.724916)
			(stroke
				(width 0.1)
				(type default)
			)
			(layer "B.Fab")
		)
		(fp_line
			(start -1.1049 -0.724916)
			(end 1.1049 -0.724916)
			(stroke
				(width 0.1)
				(type default)
			)
			(layer "B.Fab")
		)
		(fp_line
			(start 1.1049 0.724916)
			(end -1.1049 0.724916)
			(stroke
				(width 0.1)
				(type default)
			)
			(layer "B.Fab")
		)
		(fp_line
			(start -1.1049 0.724916)
			(end -1.1049 -0.724916)
			(stroke
				(width 0.1)
				(type default)
			)
			(layer "B.Fab")
		)
		(pad "1" smd rect
			(at 0.889 0 90)
			(size 1.016 1.27)
			(layers "B.Cu" "B.Mask" "B.Paste")
			(net "SW_P12V_AUX_P0V9_RETIMER_CPU1_FLT")
		)
		(pad "2" smd rect
			(at -0.889 0 90)
			(size 1.016 1.27)
			(layers "B.Cu" "B.Mask" "B.Paste")
			(net "GND")
		)
	)
	(footprint ""
		(layer "B.Cu")
		(at 400.964146 -354.439728 -90)
		(property "Reference" "R6129"
			(at 0 0 90)
			(layer "B.SilkS")
			(hide yes)
			(effects
				(font
					(size 1.27 1.27)
				)
				(justify mirror)
			)
		)
		(property "Value" ""
			(at 0 0 90)
			(layer "B.Fab")
			(effects
				(font
					(size 1.27 1.27)
				)
				(justify mirror)
			)
		)
		(duplicate_pad_numbers_are_jumpers no)
		(fp_line
			(start -0.7874 0.4064)
			(end 0.7874 0.4064)
			(stroke
				(width 0.1524)
				(type default)
			)
			(layer "B.SilkS")
		)
		(fp_line
			(start 0.7874 0.4064)
			(end 0.7874 -0.4064)
			(stroke
				(width 0.1524)
				(type default)
			)
			(layer "B.SilkS")
		)
		(fp_line
			(start -0.7874 -0.4064)
			(end -0.7874 0.4064)
			(stroke
				(width 0.1524)
				(type default)
			)
			(layer "B.SilkS")
		)
		(fp_line
			(start 0.7874 -0.4064)
			(end -0.7874 -0.4064)
			(stroke
				(width 0.1524)
				(type default)
			)
			(layer "B.SilkS")
		)
		(fp_line
			(start -0.67945 0.3048)
			(end -0.120396 0.3048)
			(stroke
				(width 0.1)
				(type default)
			)
			(layer "B.Fab")
		)
		(fp_line
			(start -0.120396 0.3048)
			(end -0.120396 0.2794)
			(stroke
				(width 0.1)
				(type default)
			)
			(layer "B.Fab")
		)
		(fp_line
			(start 0.12065 0.3048)
			(end 0.67945 0.3048)
			(stroke
				(width 0.1)
				(type default)
			)
			(layer "B.Fab")
		)
		(fp_line
			(start 0.67945 0.3048)
			(end 0.67945 -0.305054)
			(stroke
				(width 0.1)
				(type default)
			)
			(layer "B.Fab")
		)
		(fp_line
			(start -0.120396 0.2794)
			(end 0.12065 0.2794)
			(stroke
				(width 0.1)
				(type default)
			)
			(layer "B.Fab")
		)
		(fp_line
			(start 0.12065 0.2794)
			(end 0.12065 0.3048)
			(stroke
				(width 0.1)
				(type default)
			)
			(layer "B.Fab")
		)
		(fp_line
			(start -0.12065 -0.2794)
			(end -0.12065 -0.3048)
			(stroke
				(width 0.1)
				(type default)
			)
			(layer "B.Fab")
		)
		(fp_line
			(start 0.12065 -0.2794)
			(end -0.12065 -0.2794)
			(stroke
				(width 0.1)
				(type default)
			)
			(layer "B.Fab")
		)
		(fp_line
			(start -0.67945 -0.3048)
			(end -0.67945 0.3048)
			(stroke
				(width 0.1)
				(type default)
			)
			(layer "B.Fab")
		)
		(fp_line
			(start -0.12065 -0.3048)
			(end -0.67945 -0.3048)
			(stroke
				(width 0.1)
				(type default)
			)
			(layer "B.Fab")
		)
		(fp_line
			(start 0.12065 -0.305054)
			(end 0.12065 -0.2794)
			(stroke
				(width 0.1)
				(type default)
			)
			(layer "B.Fab")
		)
		(fp_line
			(start 0.67945 -0.305054)
			(end 0.12065 -0.305054)
			(stroke
				(width 0.1)
				(type default)
			)
			(layer "B.Fab")
		)
		(pad "1" smd circle
			(at 0.40005 0 90)
			(size 0 0)
			(layers "B.Cu" "B.Mask" "B.Paste")
			(net "FM_BOARD_SKU_ID0")
		)
		(pad "2" smd circle
			(at -0.40005 0 90)
			(size 0 0)
			(layers "B.Cu" "B.Mask" "B.Paste")
			(net "GND")
		)
	)
)
